(kicad_sch (version 20230121) (generator eeschema)

  (paper "A3")

  (title_block
    (title "Kria K26 Devboard")
    (date "2024-03-26")
    (rev "1.2.5")
    (comment 1 "www.antmicro.com")
    (comment 2 "Antmicro Ltd.")
  )

  (junction (at 132.715 97.155) (diameter 0) (color 0 0 0 0)
  )
  (junction (at 137.795 179.705) (diameter 0) (color 0 0 0 0)
  )
  (junction (at 81.915 179.705) (diameter 0) (color 0 0 0 0)
  )
  (junction (at 108.585 109.855) (diameter 0) (color 0 0 0 0)
  )
  (junction (at 145.415 72.39) (diameter 0) (color 0 0 0 0)
  )
  (junction (at 99.06 82.55) (diameter 0) (color 0 0 0 0)
  )
  (junction (at 107.315 85.09) (diameter 0) (color 0 0 0 0)
  )
  (junction (at 155.575 116.205) (diameter 0) (color 0 0 0 0)
  )
  (junction (at 135.255 72.39) (diameter 0) (color 0 0 0 0)
  )
  (junction (at 155.575 118.745) (diameter 0) (color 0 0 0 0)
  )

  (wire (pts (xy 113.665 103.505) (xy 134.62 103.505))
    (stroke (width 0) (type default))
  )
  (wire (pts (xy 145.415 72.39) (xy 155.575 72.39))
    (stroke (width 0) (type default))
  )
  (wire (pts (xy 175.26 180.975) (xy 181.61 180.975))
    (stroke (width 0) (type default))
  )
  (wire (pts (xy 108.585 101.6) (xy 108.585 103.505))
    (stroke (width 0) (type default))
  )
  (wire (pts (xy 262.89 176.53) (xy 266.7 176.53))
    (stroke (width 0) (type default))
  )
  (wire (pts (xy 153.67 97.155) (xy 166.37 97.155))
    (stroke (width 0) (type default))
  )
  (wire (pts (xy 241.3 175.895) (xy 241.3 173.99))
    (stroke (width 0) (type default))
  )
  (wire (pts (xy 282.575 97.155) (xy 289.56 97.155))
    (stroke (width 0) (type default))
  )
  (wire (pts (xy 99.06 82.55) (xy 116.205 82.55))
    (stroke (width 0) (type default))
  )
  (wire (pts (xy 153.67 113.665) (xy 155.575 113.665))
    (stroke (width 0) (type default))
  )
  (wire (pts (xy 153.67 106.045) (xy 166.37 106.045))
    (stroke (width 0) (type default))
  )
  (wire (pts (xy 106.045 101.6) (xy 108.585 101.6))
    (stroke (width 0) (type default))
  )
  (wire (pts (xy 74.295 85.09) (xy 78.105 85.09))
    (stroke (width 0) (type default))
  )
  (wire (pts (xy 132.715 97.155) (xy 132.715 99.695))
    (stroke (width 0) (type default))
  )
  (wire (pts (xy 113.665 184.785) (xy 115.57 184.785))
    (stroke (width 0) (type default))
  )
  (wire (pts (xy 89.535 179.705) (xy 89.535 180.975))
    (stroke (width 0) (type default))
  )
  (wire (pts (xy 135.255 72.39) (xy 145.415 72.39))
    (stroke (width 0) (type default))
  )
  (wire (pts (xy 262.89 173.99) (xy 266.7 173.99))
    (stroke (width 0) (type default))
  )
  (wire (pts (xy 132.08 72.39) (xy 135.255 72.39))
    (stroke (width 0) (type default))
  )
  (wire (pts (xy 264.795 180.975) (xy 264.795 179.07))
    (stroke (width 0) (type default))
  )
  (wire (pts (xy 137.795 179.705) (xy 137.795 180.975))
    (stroke (width 0) (type default))
  )
  (wire (pts (xy 155.575 116.205) (xy 155.575 118.745))
    (stroke (width 0) (type default))
  )
  (wire (pts (xy 108.585 109.855) (xy 134.62 109.855))
    (stroke (width 0) (type default))
  )
  (wire (pts (xy 130.81 113.665) (xy 134.62 113.665))
    (stroke (width 0) (type default))
  )
  (wire (pts (xy 175.26 178.435) (xy 181.61 178.435))
    (stroke (width 0) (type default))
  )
  (wire (pts (xy 134.62 99.695) (xy 132.715 99.695))
    (stroke (width 0) (type default))
  )
  (polyline (pts (xy 217.805 16.51) (xy 217.805 277.495))
    (stroke (width 0) (type default))
  )

  (wire (pts (xy 155.575 73.66) (xy 155.575 72.39))
    (stroke (width 0) (type default))
  )
  (wire (pts (xy 153.67 109.855) (xy 160.655 109.855))
    (stroke (width 0) (type default))
  )
  (wire (pts (xy 76.2 88.9) (xy 76.2 87.63))
    (stroke (width 0) (type default))
  )
  (wire (pts (xy 238.125 95.25) (xy 238.125 93.98))
    (stroke (width 0) (type default))
  )
  (wire (pts (xy 97.155 85.09) (xy 107.315 85.09))
    (stroke (width 0) (type default))
  )
  (wire (pts (xy 155.575 113.665) (xy 155.575 116.205))
    (stroke (width 0) (type default))
  )
  (wire (pts (xy 177.165 184.785) (xy 177.165 183.515))
    (stroke (width 0) (type default))
  )
  (wire (pts (xy 259.715 97.155) (xy 263.525 97.155))
    (stroke (width 0) (type default))
  )
  (wire (pts (xy 113.665 186.055) (xy 113.665 184.785))
    (stroke (width 0) (type default))
  )
  (wire (pts (xy 155.575 116.205) (xy 153.67 116.205))
    (stroke (width 0) (type default))
  )
  (wire (pts (xy 113.665 85.09) (xy 113.665 103.505))
    (stroke (width 0) (type default))
  )
  (wire (pts (xy 99.06 87.63) (xy 99.06 82.55))
    (stroke (width 0) (type default))
  )
  (wire (pts (xy 134.62 106.045) (xy 116.205 106.045))
    (stroke (width 0) (type default))
  )
  (wire (pts (xy 241.3 173.99) (xy 239.395 173.99))
    (stroke (width 0) (type default))
  )
  (wire (pts (xy 137.795 179.705) (xy 156.21 179.705))
    (stroke (width 0) (type default))
  )
  (polyline (pts (xy 401.955 145.415) (xy 18.415 145.415))
    (stroke (width 0) (type default))
  )

  (wire (pts (xy 285.75 176.53) (xy 288.925 176.53))
    (stroke (width 0) (type default))
  )
  (wire (pts (xy 238.125 93.98) (xy 235.585 93.98))
    (stroke (width 0) (type default))
  )
  (wire (pts (xy 76.835 179.705) (xy 81.915 179.705))
    (stroke (width 0) (type default))
  )
  (wire (pts (xy 74.295 82.55) (xy 78.105 82.55))
    (stroke (width 0) (type default))
  )
  (wire (pts (xy 175.26 183.515) (xy 177.165 183.515))
    (stroke (width 0) (type default))
  )
  (wire (pts (xy 153.67 118.745) (xy 155.575 118.745))
    (stroke (width 0) (type default))
  )
  (wire (pts (xy 160.655 109.855) (xy 160.655 115.57))
    (stroke (width 0) (type default))
  )
  (wire (pts (xy 261.62 99.695) (xy 263.525 99.695))
    (stroke (width 0) (type default))
  )
  (wire (pts (xy 132.715 97.155) (xy 134.62 97.155))
    (stroke (width 0) (type default))
  )
  (wire (pts (xy 116.205 82.55) (xy 116.205 106.045))
    (stroke (width 0) (type default))
  )
  (wire (pts (xy 74.295 97.79) (xy 74.295 99.695))
    (stroke (width 0) (type default))
  )
  (wire (pts (xy 76.2 87.63) (xy 78.105 87.63))
    (stroke (width 0) (type default))
  )
  (wire (pts (xy 153.67 103.505) (xy 166.37 103.505))
    (stroke (width 0) (type default))
  )
  (wire (pts (xy 259.715 94.615) (xy 263.525 94.615))
    (stroke (width 0) (type default))
  )
  (wire (pts (xy 155.575 118.745) (xy 155.575 120.65))
    (stroke (width 0) (type default))
  )
  (wire (pts (xy 264.795 179.07) (xy 266.7 179.07))
    (stroke (width 0) (type default))
  )
  (wire (pts (xy 282.575 94.615) (xy 289.56 94.615))
    (stroke (width 0) (type default))
  )
  (wire (pts (xy 108.585 108.585) (xy 108.585 109.855))
    (stroke (width 0) (type default))
  )
  (wire (pts (xy 129.54 97.155) (xy 132.715 97.155))
    (stroke (width 0) (type default))
  )
  (wire (pts (xy 145.415 73.66) (xy 145.415 72.39))
    (stroke (width 0) (type default))
  )
  (wire (pts (xy 107.315 87.63) (xy 107.315 85.09))
    (stroke (width 0) (type default))
  )
  (wire (pts (xy 153.67 175.895) (xy 156.21 175.895))
    (stroke (width 0) (type default))
  )
  (wire (pts (xy 134.62 179.705) (xy 137.795 179.705))
    (stroke (width 0) (type default))
  )
  (wire (pts (xy 81.915 179.705) (xy 81.915 180.975))
    (stroke (width 0) (type default))
  )
  (wire (pts (xy 113.03 182.245) (xy 115.57 182.245))
    (stroke (width 0) (type default))
  )
  (wire (pts (xy 98.425 117.475) (xy 100.965 117.475))
    (stroke (width 0) (type default))
  )
  (wire (pts (xy 135.255 73.66) (xy 135.255 72.39))
    (stroke (width 0) (type default))
  )
  (wire (pts (xy 153.67 99.695) (xy 166.37 99.695))
    (stroke (width 0) (type default))
  )
  (wire (pts (xy 97.155 82.55) (xy 99.06 82.55))
    (stroke (width 0) (type default))
  )
  (wire (pts (xy 81.915 179.705) (xy 89.535 179.705))
    (stroke (width 0) (type default))
  )
  (wire (pts (xy 71.755 97.79) (xy 74.295 97.79))
    (stroke (width 0) (type default))
  )
  (wire (pts (xy 285.75 173.99) (xy 288.925 173.99))
    (stroke (width 0) (type default))
  )
  (wire (pts (xy 261.62 101.6) (xy 261.62 99.695))
    (stroke (width 0) (type default))
  )
  (wire (pts (xy 107.315 85.09) (xy 113.665 85.09))
    (stroke (width 0) (type default))
  )
  (wire (pts (xy 108.585 109.855) (xy 108.585 112.395))
    (stroke (width 0) (type default))
  )
  (wire (pts (xy 113.03 179.705) (xy 115.57 179.705))
    (stroke (width 0) (type default))
  )

  (text "ETH GTH REFCLK: 125MHz LVDS" (at 221.615 160.02 0)
    (effects (font (size 2.54 2.54) (thickness 0.508) bold) (justify left bottom))
  )
  (text "USB GTH REFCLK: 26MHz LVDS" (at 53.975 160.02 0)
    (effects (font (size 2.54 2.54) (thickness 0.508) bold) (justify left bottom))
  )
  (text "DisplayPort GTH REFCLK: 27MHz LVDS" (at 221.615 50.8 0)
    (effects (font (size 2.54 2.54) (thickness 0.508) bold) (justify left bottom))
  )
  (text "PCIe GTH REFCLK: 2x100MHz HCSL" (at 53.975 49.53 0)
    (effects (font (size 2.54 2.54) (thickness 0.508) bold) (justify left bottom))
  )
  (text "CLK pinswapped \nto improve routing" (at 116.84 105.41 0)
    (effects (font (size 1.27 1.27)) (justify left bottom))
  )

  (label "CLK_100M_P" (at 100.965 82.55 0) (fields_autoplaced)
    (effects (font (size 1.27 1.27)) (justify left bottom))
  )
  (label "CLK_100M_N" (at 100.965 85.09 0) (fields_autoplaced)
    (effects (font (size 1.27 1.27)) (justify left bottom))
  )

  (global_label "PS_3V3" (shape input) (at 262.89 173.99 180) (fields_autoplaced)
    (effects (font (size 1.27 1.27)) (justify right))
    (property "Intersheetrefs" "${INTERSHEET_REFS}" (at 66.04 27.94 0)
      (effects (font (size 1.27 1.27)) hide)
    )
  )
  (global_label "PS_3V3" (shape input) (at 76.835 179.705 180) (fields_autoplaced)
    (effects (font (size 1.27 1.27)) (justify right))
    (property "Intersheetrefs" "${INTERSHEET_REFS}" (at 8.255 31.115 0)
      (effects (font (size 1.27 1.27)) hide)
    )
  )
  (global_label "PS_3V3" (shape input) (at 239.395 173.99 180) (fields_autoplaced)
    (effects (font (size 1.27 1.27)) (justify right))
    (property "Intersheetrefs" "${INTERSHEET_REFS}" (at 42.545 27.94 0)
      (effects (font (size 1.27 1.27)) hide)
    )
  )
  (global_label "PS_3V3" (shape input) (at 71.755 97.79 180) (fields_autoplaced)
    (effects (font (size 1.27 1.27)) (justify right))
    (property "Intersheetrefs" "${INTERSHEET_REFS}" (at 41.275 64.77 0)
      (effects (font (size 1.27 1.27)) hide)
    )
  )
  (global_label "PS_3V3" (shape input) (at 74.295 82.55 180) (fields_autoplaced)
    (effects (font (size 1.27 1.27)) (justify right))
    (property "Intersheetrefs" "${INTERSHEET_REFS}" (at 43.815 49.53 0)
      (effects (font (size 1.27 1.27)) hide)
    )
  )
  (global_label "PS_3V3" (shape input) (at 113.03 179.705 180) (fields_autoplaced)
    (effects (font (size 1.27 1.27)) (justify right))
    (property "Intersheetrefs" "${INTERSHEET_REFS}" (at 44.45 31.115 0)
      (effects (font (size 1.27 1.27)) hide)
    )
  )
  (global_label "PS_3V3" (shape input) (at 132.08 72.39 180) (fields_autoplaced)
    (effects (font (size 1.27 1.27)) (justify right))
    (property "Intersheetrefs" "${INTERSHEET_REFS}" (at 57.15 34.29 0)
      (effects (font (size 1.27 1.27)) hide)
    )
  )
  (global_label "PS_3V3" (shape input) (at 129.54 97.155 180) (fields_autoplaced)
    (effects (font (size 1.27 1.27)) (justify right))
    (property "Intersheetrefs" "${INTERSHEET_REFS}" (at 54.61 59.055 0)
      (effects (font (size 1.27 1.27)) hide)
    )
  )
  (global_label "PS_3V3" (shape input) (at 235.585 93.98 180) (fields_autoplaced)
    (effects (font (size 1.27 1.27)) (justify right))
    (property "Intersheetrefs" "${INTERSHEET_REFS}" (at 40.005 35.56 0)
      (effects (font (size 1.27 1.27)) hide)
    )
  )
  (global_label "PS_3V3" (shape input) (at 106.045 101.6 180) (fields_autoplaced)
    (effects (font (size 1.27 1.27)) (justify right))
    (property "Intersheetrefs" "${INTERSHEET_REFS}" (at 19.685 146.05 0)
      (effects (font (size 1.27 1.27)) hide)
    )
  )
  (global_label "PS_3V3" (shape input) (at 259.715 94.615 180) (fields_autoplaced)
    (effects (font (size 1.27 1.27)) (justify right))
    (property "Intersheetrefs" "${INTERSHEET_REFS}" (at 64.135 36.195 0)
      (effects (font (size 1.27 1.27)) hide)
    )
  )
  (global_label "PS_3V3" (shape input) (at 153.67 175.895 180) (fields_autoplaced)
    (effects (font (size 1.27 1.27)) (justify right))
    (property "Intersheetrefs" "${INTERSHEET_REFS}" (at 85.09 27.305 0)
      (effects (font (size 1.27 1.27)) hide)
    )
  )

  (hierarchical_label "GTR_REFCLK1_C2M_N" (shape input) (at 181.61 180.975 0) (fields_autoplaced)
    (effects (font (size 1.27 1.27)) (justify left))
  )
  (hierarchical_label "GTR_REFCLK3_C2M_N" (shape input) (at 166.37 99.695 0) (fields_autoplaced)
    (effects (font (size 1.27 1.27)) (justify left))
  )
  (hierarchical_label "GTR_REFCLK2_C2M_N" (shape input) (at 288.925 176.53 0) (fields_autoplaced)
    (effects (font (size 1.27 1.27)) (justify left))
  )
  (hierarchical_label "GTR_REFCLK1_C2M_P" (shape input) (at 181.61 178.435 0) (fields_autoplaced)
    (effects (font (size 1.27 1.27)) (justify left))
  )
  (hierarchical_label "PS_CLK_EN" (shape input) (at 259.715 97.155 180) (fields_autoplaced)
    (effects (font (size 1.27 1.27)) (justify right))
  )
  (hierarchical_label "PS_CLK_EN" (shape input) (at 262.89 176.53 180) (fields_autoplaced)
    (effects (font (size 1.27 1.27)) (justify right))
  )
  (hierarchical_label "GTR_REFCLK0_C2M_P" (shape input) (at 289.56 94.615 0) (fields_autoplaced)
    (effects (font (size 1.27 1.27)) (justify left))
  )
  (hierarchical_label "GTR_REFCLK3_C2M_P" (shape input) (at 166.37 97.155 0) (fields_autoplaced)
    (effects (font (size 1.27 1.27)) (justify left))
  )
  (hierarchical_label "PS_CLK_EN" (shape input) (at 98.425 117.475 180) (fields_autoplaced)
    (effects (font (size 1.27 1.27)) (justify right))
  )
  (hierarchical_label "GTR_REFCLK3_P" (shape input) (at 166.37 103.505 0) (fields_autoplaced)
    (effects (font (size 1.27 1.27)) (justify left))
  )
  (hierarchical_label "~{M2_CLKREQ}" (shape input) (at 130.81 113.665 180) (fields_autoplaced)
    (effects (font (size 1.27 1.27)) (justify right))
  )
  (hierarchical_label "GTR_REFCLK2_C2M_P" (shape input) (at 288.925 173.99 0) (fields_autoplaced)
    (effects (font (size 1.27 1.27)) (justify left))
  )
  (hierarchical_label "GTR_REFCLK0_C2M_N" (shape input) (at 289.56 97.155 0) (fields_autoplaced)
    (effects (font (size 1.27 1.27)) (justify left))
  )
  (hierarchical_label "GTR_REFCLK3_N" (shape input) (at 166.37 106.045 0) (fields_autoplaced)
    (effects (font (size 1.27 1.27)) (justify left))
  )
  (hierarchical_label "PS_CLK_EN" (shape input) (at 113.03 182.245 180) (fields_autoplaced)
    (effects (font (size 1.27 1.27)) (justify right))
  )
  (hierarchical_label "PS_CLK_EN" (shape input) (at 74.295 85.09 180) (fields_autoplaced)
    (effects (font (size 1.27 1.27)) (justify right))
  )

  (symbol (lib_id "kria-k26-devboard:Oscillator_125MHz_AX3DA") (at 266.7 173.99 0) (unit 1)
    (in_bom yes) (on_board yes) (dnp no) (fields_autoplaced)
    (property "Reference" "Y3" (at 276.225 163.83 0)
      (effects (font (size 1.27 1.27)))
    )
    (property "Value" "Oscillator_125MHz_AX3DA" (at 300.99 180.34 0)
      (effects (font (size 1.27 1.27) (thickness 0.15)) (justify left bottom) hide)
    )
    (property "Footprint" "kria-k26-devboard-footprints:Oscillator_SMD_Abracon_AX3_3.2x2.5x1mm" (at 300.99 182.88 0)
      (effects (font (size 1.27 1.27) (thickness 0.15)) (justify left bottom) hide)
    )
    (property "Datasheet" "https://abracon.com/datasheets/AX3.pdf" (at 300.99 185.42 0)
      (effects (font (size 1.27 1.27) (thickness 0.15)) (justify left bottom) hide)
    )
    (property "MPN" "AX3DAF1-125.0000" (at 276.225 166.37 0)
      (effects (font (size 1.27 1.27) (thickness 0.15)))
    )
    (property "Manufacturer" "Abracon" (at 300.99 190.5 0)
      (effects (font (size 1.27 1.27) (thickness 0.15)) (justify left bottom) hide)
    )
    (property "Author" "Antmicro" (at 300.99 193.04 0)
      (effects (font (size 1.27 1.27) (thickness 0.15)) (justify left bottom) hide)
    )
    (property "License" "Apache-2.0" (at 300.99 195.58 0)
      (effects (font (size 1.27 1.27) (thickness 0.15)) (justify left bottom) hide)
    )
    (property "Val" "125 MHz" (at 276.225 168.91 0)
      (effects (font (size 1.27 1.27) (thickness 0.15)))
    )
    (pin "1")
    (pin "2")
    (pin "3")
    (pin "4")
    (pin "5")
    (pin "6")
    (instances
      (project "kria-k26-devboard"
        (path ""
          (reference "Y3") (unit 1)
        )
      )
    )
  )

  (symbol (lib_id "kria-k26-devboard:GND") (at 264.795 180.975 0) (unit 1)
    (in_bom yes) (on_board yes) (dnp no) (fields_autoplaced)
    (property "Reference" "#PWR049" (at 264.795 187.325 0)
      (effects (font (size 1.27 1.27)) hide)
    )
    (property "Value" "GND" (at 264.795 186.055 0)
      (effects (font (size 1.27 1.27)))
    )
    (property "Footprint" "" (at 273.685 188.595 0)
      (effects (font (size 1.27 1.27) (thickness 0.15)) (justify left bottom) hide)
    )
    (property "Datasheet" "" (at 273.685 193.675 0)
      (effects (font (size 1.27 1.27) (thickness 0.15)) (justify left bottom) hide)
    )
    (property "Author" "Antmicro" (at 273.685 188.595 0)
      (effects (font (size 1.27 1.27) (thickness 0.15)) (justify left bottom) hide)
    )
    (property "License" "Apache-2.0" (at 273.685 191.135 0)
      (effects (font (size 1.27 1.27) (thickness 0.15)) (justify left bottom) hide)
    )
    (pin "1")
    (instances
      (project "kria-k26-devboard"
        (path ""
          (reference "#PWR049") (unit 1)
        )
      )
    )
  )

  (symbol (lib_id "kria-k26-devboard:C_100n_0402") (at 241.3 175.895 270) (unit 1)
    (in_bom yes) (on_board yes) (dnp no) (fields_autoplaced)
    (property "Reference" "C28" (at 243.84 177.1713 90)
      (effects (font (size 1.524 1.524)) (justify left))
    )
    (property "Value" "C_100n_0402" (at 231.14 196.215 0)
      (effects (font (size 1.27 1.27) (thickness 0.15)) (justify left bottom) hide)
    )
    (property "Footprint" "kria-k26-devboard-footprints:C_0402_1005Metric" (at 228.6 196.215 0)
      (effects (font (size 1.27 1.27) (thickness 0.15)) (justify left bottom) hide)
    )
    (property "Datasheet" "https://search.murata.co.jp/Ceramy/image/img/A01X/G101/ENG/GRM155R61H104KE14-01.pdf" (at 226.06 196.215 0)
      (effects (font (size 1.27 1.27) (thickness 0.15)) (justify left bottom) hide)
    )
    (property "Manufacturer" "Murata" (at 220.98 196.215 0)
      (effects (font (size 1.27 1.27) (thickness 0.15)) (justify left bottom) hide)
    )
    (property "MPN" "GRM155R61H104KE14D" (at 223.52 196.215 0)
      (effects (font (size 1.27 1.27) (thickness 0.15)) (justify left bottom) hide)
    )
    (property "Val" "100n" (at 243.84 180.3462 90)
      (effects (font (size 1.27 1.27) (thickness 0.15)) (justify left))
    )
    (property "License" "Apache-2.0" (at 218.44 196.215 0)
      (effects (font (size 1.27 1.27) (thickness 0.15)) (justify left bottom) hide)
    )
    (property "Author" "Antmicro" (at 215.9 196.215 0)
      (effects (font (size 1.27 1.27) (thickness 0.15)) (justify left bottom) hide)
    )
    (property "Voltage" "50V" (at 213.36 196.215 0)
      (effects (font (size 1.27 1.27)) (justify left bottom) hide)
    )
    (property "Dielectric" "X5R" (at 210.82 196.215 0)
      (effects (font (size 1.27 1.27)) (justify left bottom) hide)
    )
    (pin "1")
    (pin "2")
    (instances
      (project "kria-k26-devboard"
        (path ""
          (reference "C28") (unit 1)
        )
      )
    )
  )

  (symbol (lib_id "kria-k26-devboard:GND") (at 241.3 180.975 0) (unit 1)
    (in_bom yes) (on_board yes) (dnp no) (fields_autoplaced)
    (property "Reference" "#PWR048" (at 241.3 187.325 0)
      (effects (font (size 1.27 1.27)) hide)
    )
    (property "Value" "GND" (at 241.3 186.055 0)
      (effects (font (size 1.27 1.27)))
    )
    (property "Footprint" "" (at 250.19 188.595 0)
      (effects (font (size 1.27 1.27) (thickness 0.15)) (justify left bottom) hide)
    )
    (property "Datasheet" "" (at 250.19 193.675 0)
      (effects (font (size 1.27 1.27) (thickness 0.15)) (justify left bottom) hide)
    )
    (property "Author" "Antmicro" (at 250.19 188.595 0)
      (effects (font (size 1.27 1.27) (thickness 0.15)) (justify left bottom) hide)
    )
    (property "License" "Apache-2.0" (at 250.19 191.135 0)
      (effects (font (size 1.27 1.27) (thickness 0.15)) (justify left bottom) hide)
    )
    (pin "1")
    (instances
      (project "kria-k26-devboard"
        (path ""
          (reference "#PWR048") (unit 1)
        )
      )
    )
  )

  (symbol (lib_id "kria-k26-devboard:Oscillator_27MHz_JU6") (at 263.525 94.615 0) (unit 1)
    (in_bom yes) (on_board yes) (dnp no) (fields_autoplaced)
    (property "Reference" "U9" (at 273.05 85.09 0)
      (effects (font (size 1.524 1.524)))
    )
    (property "Value" "Oscillator_27MHz_JU6" (at 272.415 89.535 0)
      (effects (font (size 1.27 1.27) (thickness 0.15)) hide)
    )
    (property "Footprint" "kria-k26-devboard-footprints:Oscillator_SMD_JU6_7x5mm_P2.54mm" (at 296.545 102.235 0)
      (effects (font (size 1.27 1.27) (thickness 0.15)) (justify left bottom) hide)
    )
    (property "Datasheet" "https://www.idt.com/document/dst/xl-family-low-phase-noise-quartz-based-pll-oscillators-datasheet" (at 296.545 104.775 0)
      (effects (font (size 1.27 1.27) (thickness 0.15)) (justify left bottom) hide)
    )
    (property "MPN" "XLL736027.000000X" (at 273.05 87.63 0)
      (effects (font (size 1.27 1.27) (thickness 0.15)))
    )
    (property "Manufacturer" "Renesas" (at 296.545 109.855 0)
      (effects (font (size 1.27 1.27) (thickness 0.15)) (justify left bottom) hide)
    )
    (property "Author" "Antmicro" (at 296.545 112.395 0)
      (effects (font (size 1.27 1.27) (thickness 0.15)) (justify left bottom) hide)
    )
    (property "License" "Apache-2.0" (at 296.545 114.935 0)
      (effects (font (size 1.27 1.27) (thickness 0.15)) (justify left bottom) hide)
    )
    (property "Val" "27 MHz" (at 273.05 90.17 0)
      (effects (font (size 1.27 1.27) (thickness 0.15)))
    )
    (pin "1")
    (pin "2")
    (pin "3")
    (pin "4")
    (pin "5")
    (pin "6")
    (instances
      (project "kria-k26-devboard"
        (path ""
          (reference "U9") (unit 1)
        )
      )
    )
  )

  (symbol (lib_id "kria-k26-devboard:C_100n_0402") (at 238.125 95.25 270) (unit 1)
    (in_bom yes) (on_board yes) (dnp no) (fields_autoplaced)
    (property "Reference" "C27" (at 241.3 96.5263 90)
      (effects (font (size 1.524 1.524)) (justify left))
    )
    (property "Value" "C_100n_0402" (at 227.965 115.57 0)
      (effects (font (size 1.27 1.27) (thickness 0.15)) (justify left bottom) hide)
    )
    (property "Footprint" "kria-k26-devboard-footprints:C_0402_1005Metric" (at 225.425 115.57 0)
      (effects (font (size 1.27 1.27) (thickness 0.15)) (justify left bottom) hide)
    )
    (property "Datasheet" "https://search.murata.co.jp/Ceramy/image/img/A01X/G101/ENG/GRM155R61H104KE14-01.pdf" (at 222.885 115.57 0)
      (effects (font (size 1.27 1.27) (thickness 0.15)) (justify left bottom) hide)
    )
    (property "Manufacturer" "Murata" (at 217.805 115.57 0)
      (effects (font (size 1.27 1.27) (thickness 0.15)) (justify left bottom) hide)
    )
    (property "MPN" "GRM155R61H104KE14D" (at 220.345 115.57 0)
      (effects (font (size 1.27 1.27) (thickness 0.15)) (justify left bottom) hide)
    )
    (property "Val" "100n" (at 241.3 99.7012 90)
      (effects (font (size 1.27 1.27) (thickness 0.15)) (justify left))
    )
    (property "License" "Apache-2.0" (at 215.265 115.57 0)
      (effects (font (size 1.27 1.27) (thickness 0.15)) (justify left bottom) hide)
    )
    (property "Author" "Antmicro" (at 212.725 115.57 0)
      (effects (font (size 1.27 1.27) (thickness 0.15)) (justify left bottom) hide)
    )
    (property "Voltage" "50V" (at 210.185 115.57 0)
      (effects (font (size 1.27 1.27)) (justify left bottom) hide)
    )
    (property "Dielectric" "X5R" (at 207.645 115.57 0)
      (effects (font (size 1.27 1.27)) (justify left bottom) hide)
    )
    (pin "1")
    (pin "2")
    (instances
      (project "kria-k26-devboard"
        (path ""
          (reference "C27") (unit 1)
        )
      )
    )
  )

  (symbol (lib_id "kria-k26-devboard:GND") (at 238.125 100.33 0) (unit 1)
    (in_bom yes) (on_board yes) (dnp no) (fields_autoplaced)
    (property "Reference" "#PWR047" (at 238.125 106.68 0)
      (effects (font (size 1.27 1.27)) hide)
    )
    (property "Value" "GND" (at 238.125 105.41 0)
      (effects (font (size 1.27 1.27)))
    )
    (property "Footprint" "" (at 247.015 107.95 0)
      (effects (font (size 1.27 1.27) (thickness 0.15)) (justify left bottom) hide)
    )
    (property "Datasheet" "" (at 247.015 113.03 0)
      (effects (font (size 1.27 1.27) (thickness 0.15)) (justify left bottom) hide)
    )
    (property "Author" "Antmicro" (at 247.015 107.95 0)
      (effects (font (size 1.27 1.27) (thickness 0.15)) (justify left bottom) hide)
    )
    (property "License" "Apache-2.0" (at 247.015 110.49 0)
      (effects (font (size 1.27 1.27) (thickness 0.15)) (justify left bottom) hide)
    )
    (pin "1")
    (instances
      (project "kria-k26-devboard"
        (path ""
          (reference "#PWR047") (unit 1)
        )
      )
    )
  )

  (symbol (lib_id "kria-k26-devboard:GND") (at 261.62 101.6 0) (unit 1)
    (in_bom yes) (on_board yes) (dnp no) (fields_autoplaced)
    (property "Reference" "#PWR050" (at 261.62 107.95 0)
      (effects (font (size 1.27 1.27)) hide)
    )
    (property "Value" "GND" (at 261.62 106.68 0)
      (effects (font (size 1.27 1.27)))
    )
    (property "Footprint" "" (at 270.51 109.22 0)
      (effects (font (size 1.27 1.27) (thickness 0.15)) (justify left bottom) hide)
    )
    (property "Datasheet" "" (at 270.51 114.3 0)
      (effects (font (size 1.27 1.27) (thickness 0.15)) (justify left bottom) hide)
    )
    (property "Author" "Antmicro" (at 270.51 109.22 0)
      (effects (font (size 1.27 1.27) (thickness 0.15)) (justify left bottom) hide)
    )
    (property "License" "Apache-2.0" (at 270.51 111.76 0)
      (effects (font (size 1.27 1.27) (thickness 0.15)) (justify left bottom) hide)
    )
    (pin "1")
    (instances
      (project "kria-k26-devboard"
        (path ""
          (reference "#PWR050") (unit 1)
        )
      )
    )
  )

  (symbol (lib_id "kria-k26-devboard:Oscillator_26MHz_ESC_2520MV") (at 115.57 179.705 0) (unit 1)
    (in_bom yes) (on_board yes) (dnp no) (fields_autoplaced)
    (property "Reference" "Y2" (at 125.095 170.18 0)
      (effects (font (size 1.27 1.27)))
    )
    (property "Value" "Oscillator_26MHz_ESC_2520MV" (at 125.095 172.085 0)
      (effects (font (size 1.27 1.27) (thickness 0.15)) hide)
    )
    (property "Footprint" "kria-k26-devboard-footprints:Oscillator_SMD_ECS_2520MV_2.5x2mm" (at 148.59 187.325 0)
      (effects (font (size 1.27 1.27) (thickness 0.15)) (justify left bottom) hide)
    )
    (property "Datasheet" "https://ecsxtal.com/store/pdf/ECS-2520MV.pdf" (at 148.59 189.865 0)
      (effects (font (size 1.27 1.27) (thickness 0.15)) (justify left bottom) hide)
    )
    (property "Manufacturer" "ECS Inc. International" (at 148.59 192.405 0)
      (effects (font (size 1.27 1.27) (thickness 0.15)) (justify left bottom) hide)
    )
    (property "MPN" "ECS-2520MVLC-260-CM-TR" (at 125.095 172.72 0)
      (effects (font (size 1.27 1.27) (thickness 0.15)))
    )
    (property "Author" "Antmicro" (at 148.59 197.485 0)
      (effects (font (size 1.27 1.27) (thickness 0.15)) (justify left bottom) hide)
    )
    (property "License" "Apache-2.0" (at 148.59 200.025 0)
      (effects (font (size 1.27 1.27) (thickness 0.15)) (justify left bottom) hide)
    )
    (property "Val" "26 MHz" (at 125.095 175.26 0)
      (effects (font (size 1.27 1.27) (thickness 0.15)))
    )
    (pin "1")
    (pin "2")
    (pin "3")
    (pin "4")
    (instances
      (project "kria-k26-devboard"
        (path ""
          (reference "Y2") (unit 1)
        )
      )
    )
  )

  (symbol (lib_id "kria-k26-devboard:SN65LVDS1_SOIC") (at 156.21 175.895 0) (unit 1)
    (in_bom yes) (on_board yes) (dnp no) (fields_autoplaced)
    (property "Reference" "U8" (at 165.735 167.64 0)
      (effects (font (size 1.27 1.27)))
    )
    (property "Value" "SN65LVDS1_SOIC" (at 187.96 180.975 0)
      (effects (font (size 1.27 1.27) (thickness 0.15)) (justify left bottom) hide)
    )
    (property "Footprint" "kria-k26-devboard-footprints:SOIC-8_3.9x4.9x1.75mm_P1.27mm" (at 187.96 183.515 0)
      (effects (font (size 1.27 1.27) (thickness 0.15)) (justify left bottom) hide)
    )
    (property "Datasheet" "https://www.ti.com/lit/ds/symlink/sn65lvds1.pdf?HQS=dis-mous-null-mousermode-dsf-pf-null-wwe&ts=1679942374500&ref_url=https%253A%252F%252Fwww.ti.com%252Fgeneral%252Fdocs%252Fsuppproductinfo.tsp%253FdistId%253D26%2526gotoUrl%253Dhttps%253A%252F%252Fwww.ti.com%252Flit%252Fgpn%252Fsn65lvds1" (at 187.96 186.055 0)
      (effects (font (size 1.27 1.27) (thickness 0.15)) (justify left bottom) hide)
    )
    (property "Manufacturer" "Texas Instruments" (at 187.96 188.595 0)
      (effects (font (size 1.27 1.27) (thickness 0.15)) (justify left bottom) hide)
    )
    (property "MPN" "SN65LVDS1DR" (at 165.735 170.18 0)
      (effects (font (size 1.27 1.27) (thickness 0.15)))
    )
    (property "Author" "Antmicro" (at 187.96 193.675 0)
      (effects (font (size 1.27 1.27) (thickness 0.15)) (justify left bottom) hide)
    )
    (property "License" "Apache-2.0" (at 187.96 196.215 0)
      (effects (font (size 1.27 1.27) (thickness 0.15)) (justify left bottom) hide)
    )
    (pin "1")
    (pin "2")
    (pin "3")
    (pin "4")
    (pin "5")
    (pin "6")
    (pin "7")
    (pin "8")
    (instances
      (project "kria-k26-devboard"
        (path ""
          (reference "U8") (unit 1)
        )
      )
    )
  )

  (symbol (lib_id "kria-k26-devboard:C_100n_0402") (at 81.915 180.975 270) (unit 1)
    (in_bom yes) (on_board yes) (dnp no)
    (property "Reference" "C22" (at 82.55 181.61 90)
      (effects (font (size 1.524 1.524)) (justify left))
    )
    (property "Value" "C_100n_0402" (at 71.755 201.295 0)
      (effects (font (size 1.27 1.27) (thickness 0.15)) (justify left bottom) hide)
    )
    (property "Footprint" "kria-k26-devboard-footprints:C_0402_1005Metric" (at 69.215 201.295 0)
      (effects (font (size 1.27 1.27) (thickness 0.15)) (justify left bottom) hide)
    )
    (property "Datasheet" "https://search.murata.co.jp/Ceramy/image/img/A01X/G101/ENG/GRM155R61H104KE14-01.pdf" (at 66.675 201.295 0)
      (effects (font (size 1.27 1.27) (thickness 0.15)) (justify left bottom) hide)
    )
    (property "Manufacturer" "Murata" (at 61.595 201.295 0)
      (effects (font (size 1.27 1.27) (thickness 0.15)) (justify left bottom) hide)
    )
    (property "MPN" "GRM155R61H104KE14D" (at 64.135 201.295 0)
      (effects (font (size 1.27 1.27) (thickness 0.15)) (justify left bottom) hide)
    )
    (property "Val" "100n" (at 82.55 185.42 90)
      (effects (font (size 1.27 1.27) (thickness 0.15)) (justify left))
    )
    (property "License" "Apache-2.0" (at 59.055 201.295 0)
      (effects (font (size 1.27 1.27) (thickness 0.15)) (justify left bottom) hide)
    )
    (property "Author" "Antmicro" (at 56.515 201.295 0)
      (effects (font (size 1.27 1.27) (thickness 0.15)) (justify left bottom) hide)
    )
    (property "Voltage" "50V" (at 53.975 201.295 0)
      (effects (font (size 1.27 1.27)) (justify left bottom) hide)
    )
    (property "Dielectric" "X5R" (at 51.435 201.295 0)
      (effects (font (size 1.27 1.27)) (justify left bottom) hide)
    )
    (pin "1")
    (pin "2")
    (instances
      (project "kria-k26-devboard"
        (path ""
          (reference "C22") (unit 1)
        )
      )
    )
  )

  (symbol (lib_id "kria-k26-devboard:C_100n_0402") (at 89.535 180.975 270) (unit 1)
    (in_bom yes) (on_board yes) (dnp no)
    (property "Reference" "C25" (at 90.17 181.61 90)
      (effects (font (size 1.524 1.524)) (justify left))
    )
    (property "Value" "C_100n_0402" (at 79.375 201.295 0)
      (effects (font (size 1.27 1.27) (thickness 0.15)) (justify left bottom) hide)
    )
    (property "Footprint" "kria-k26-devboard-footprints:C_0402_1005Metric" (at 76.835 201.295 0)
      (effects (font (size 1.27 1.27) (thickness 0.15)) (justify left bottom) hide)
    )
    (property "Datasheet" "https://search.murata.co.jp/Ceramy/image/img/A01X/G101/ENG/GRM155R61H104KE14-01.pdf" (at 74.295 201.295 0)
      (effects (font (size 1.27 1.27) (thickness 0.15)) (justify left bottom) hide)
    )
    (property "Manufacturer" "Murata" (at 69.215 201.295 0)
      (effects (font (size 1.27 1.27) (thickness 0.15)) (justify left bottom) hide)
    )
    (property "MPN" "GRM155R61H104KE14D" (at 71.755 201.295 0)
      (effects (font (size 1.27 1.27) (thickness 0.15)) (justify left bottom) hide)
    )
    (property "Val" "100n" (at 90.17 185.42 90)
      (effects (font (size 1.27 1.27) (thickness 0.15)) (justify left))
    )
    (property "License" "Apache-2.0" (at 66.675 201.295 0)
      (effects (font (size 1.27 1.27) (thickness 0.15)) (justify left bottom) hide)
    )
    (property "Author" "Antmicro" (at 64.135 201.295 0)
      (effects (font (size 1.27 1.27) (thickness 0.15)) (justify left bottom) hide)
    )
    (property "Voltage" "50V" (at 61.595 201.295 0)
      (effects (font (size 1.27 1.27)) (justify left bottom) hide)
    )
    (property "Dielectric" "X5R" (at 59.055 201.295 0)
      (effects (font (size 1.27 1.27)) (justify left bottom) hide)
    )
    (pin "1")
    (pin "2")
    (instances
      (project "kria-k26-devboard"
        (path ""
          (reference "C25") (unit 1)
        )
      )
    )
  )

  (symbol (lib_id "kria-k26-devboard:GND") (at 113.665 186.055 0) (unit 1)
    (in_bom yes) (on_board yes) (dnp no) (fields_autoplaced)
    (property "Reference" "#PWR038" (at 113.665 192.405 0)
      (effects (font (size 1.27 1.27)) hide)
    )
    (property "Value" "GND" (at 113.665 191.135 0)
      (effects (font (size 1.27 1.27)))
    )
    (property "Footprint" "" (at 122.555 193.675 0)
      (effects (font (size 1.27 1.27) (thickness 0.15)) (justify left bottom) hide)
    )
    (property "Datasheet" "" (at 122.555 198.755 0)
      (effects (font (size 1.27 1.27) (thickness 0.15)) (justify left bottom) hide)
    )
    (property "Author" "Antmicro" (at 122.555 193.675 0)
      (effects (font (size 1.27 1.27) (thickness 0.15)) (justify left bottom) hide)
    )
    (property "License" "Apache-2.0" (at 122.555 196.215 0)
      (effects (font (size 1.27 1.27) (thickness 0.15)) (justify left bottom) hide)
    )
    (pin "1")
    (instances
      (project "kria-k26-devboard"
        (path ""
          (reference "#PWR038") (unit 1)
        )
      )
    )
  )

  (symbol (lib_id "kria-k26-devboard:GND") (at 177.165 184.785 0) (unit 1)
    (in_bom yes) (on_board yes) (dnp no) (fields_autoplaced)
    (property "Reference" "#PWR044" (at 177.165 191.135 0)
      (effects (font (size 1.27 1.27)) hide)
    )
    (property "Value" "GND" (at 177.165 189.23 0)
      (effects (font (size 1.27 1.27)))
    )
    (property "Footprint" "" (at 186.055 192.405 0)
      (effects (font (size 1.27 1.27) (thickness 0.15)) (justify left bottom) hide)
    )
    (property "Datasheet" "" (at 186.055 197.485 0)
      (effects (font (size 1.27 1.27) (thickness 0.15)) (justify left bottom) hide)
    )
    (property "Author" "Antmicro" (at 186.055 192.405 0)
      (effects (font (size 1.27 1.27) (thickness 0.15)) (justify left bottom) hide)
    )
    (property "License" "Apache-2.0" (at 186.055 194.945 0)
      (effects (font (size 1.27 1.27) (thickness 0.15)) (justify left bottom) hide)
    )
    (pin "1")
    (instances
      (project "kria-k26-devboard"
        (path ""
          (reference "#PWR044") (unit 1)
        )
      )
    )
  )

  (symbol (lib_id "kria-k26-devboard:GND") (at 81.915 186.055 0) (unit 1)
    (in_bom yes) (on_board yes) (dnp no) (fields_autoplaced)
    (property "Reference" "#PWR039" (at 81.915 192.405 0)
      (effects (font (size 1.27 1.27)) hide)
    )
    (property "Value" "GND" (at 81.915 191.135 0)
      (effects (font (size 1.27 1.27)))
    )
    (property "Footprint" "" (at 90.805 193.675 0)
      (effects (font (size 1.27 1.27) (thickness 0.15)) (justify left bottom) hide)
    )
    (property "Datasheet" "" (at 90.805 198.755 0)
      (effects (font (size 1.27 1.27) (thickness 0.15)) (justify left bottom) hide)
    )
    (property "Author" "Antmicro" (at 90.805 193.675 0)
      (effects (font (size 1.27 1.27) (thickness 0.15)) (justify left bottom) hide)
    )
    (property "License" "Apache-2.0" (at 90.805 196.215 0)
      (effects (font (size 1.27 1.27) (thickness 0.15)) (justify left bottom) hide)
    )
    (pin "1")
    (instances
      (project "kria-k26-devboard"
        (path ""
          (reference "#PWR039") (unit 1)
        )
      )
    )
  )

  (symbol (lib_id "kria-k26-devboard:GND") (at 89.535 186.055 0) (unit 1)
    (in_bom yes) (on_board yes) (dnp no) (fields_autoplaced)
    (property "Reference" "#PWR042" (at 89.535 192.405 0)
      (effects (font (size 1.27 1.27)) hide)
    )
    (property "Value" "GND" (at 89.535 191.135 0)
      (effects (font (size 1.27 1.27)))
    )
    (property "Footprint" "" (at 98.425 193.675 0)
      (effects (font (size 1.27 1.27) (thickness 0.15)) (justify left bottom) hide)
    )
    (property "Datasheet" "" (at 98.425 198.755 0)
      (effects (font (size 1.27 1.27) (thickness 0.15)) (justify left bottom) hide)
    )
    (property "Author" "Antmicro" (at 98.425 193.675 0)
      (effects (font (size 1.27 1.27) (thickness 0.15)) (justify left bottom) hide)
    )
    (property "License" "Apache-2.0" (at 98.425 196.215 0)
      (effects (font (size 1.27 1.27) (thickness 0.15)) (justify left bottom) hide)
    )
    (pin "1")
    (instances
      (project "kria-k26-devboard"
        (path ""
          (reference "#PWR042") (unit 1)
        )
      )
    )
  )

  (symbol (lib_id "kria-k26-devboard:R_475R_0402") (at 160.655 115.57 270) (unit 1)
    (in_bom yes) (on_board yes) (dnp no) (fields_autoplaced)
    (property "Reference" "R22" (at 163.195 116.84 90)
      (effects (font (size 1.524 1.524)) (justify left))
    )
    (property "Value" "R_475R_0402" (at 147.955 135.89 0)
      (effects (font (size 1.27 1.27) (thickness 0.15)) (justify left bottom) hide)
    )
    (property "Footprint" "kria-k26-devboard-footprints:R_0402_1005Metric" (at 145.415 135.89 0)
      (effects (font (size 1.27 1.27) (thickness 0.15)) (justify left bottom) hide)
    )
    (property "Datasheet" "https://www.bourns.com/docs/product-datasheets/cr.pdf" (at 142.875 135.89 0)
      (effects (font (size 1.27 1.27) (thickness 0.15)) (justify left bottom) hide)
    )
    (property "Manufacturer" "Bourns" (at 137.795 135.89 0)
      (effects (font (size 1.27 1.27) (thickness 0.15)) (justify left bottom) hide)
    )
    (property "MPN" "CR0402-FX-4750GLF" (at 140.335 135.89 0)
      (effects (font (size 1.27 1.27) (thickness 0.15)) (justify left bottom) hide)
    )
    (property "Val" "475R" (at 163.195 120.0149 90)
      (effects (font (size 1.27 1.27) (thickness 0.15)) (justify left))
    )
    (property "License" "Apache-2.0" (at 135.255 135.89 0)
      (effects (font (size 1.27 1.27) (thickness 0.15)) (justify left bottom) hide)
    )
    (property "Author" "Antmicro" (at 132.715 135.89 0)
      (effects (font (size 1.27 1.27) (thickness 0.15)) (justify left bottom) hide)
    )
    (property "Tolerance" "1%" (at 150.495 135.89 0)
      (effects (font (size 1.27 1.27)) (justify left bottom) hide)
    )
    (pin "1")
    (pin "2")
    (instances
      (project "kria-k26-devboard"
        (path ""
          (reference "R22") (unit 1)
        )
      )
    )
  )

  (symbol (lib_id "kria-k26-devboard:DTC014T_SOT-416") (at 100.965 117.475 0) (unit 1)
    (in_bom yes) (on_board yes) (dnp no) (fields_autoplaced)
    (property "Reference" "Q3" (at 111.125 116.2049 0)
      (effects (font (size 1.27 1.27)) (justify left))
    )
    (property "Value" "DTC014T_SOT-416" (at 111.125 118.7449 0)
      (effects (font (size 1.27 1.27) (thickness 0.15)) (justify left) hide)
    )
    (property "Footprint" "kria-k26-devboard-footprints:SOT-416" (at 126.365 127.635 0)
      (effects (font (size 1.27 1.27) (thickness 0.15)) (justify left bottom) hide)
    )
    (property "Datasheet" "https://www.rohm.com/datasheet?p=DTC014TEB&dist=Mouser&media=referral&source=mouser.com&campaign=Mouser" (at 126.365 130.175 0)
      (effects (font (size 1.27 1.27) (thickness 0.15)) (justify left bottom) hide)
    )
    (property "Manufacturer" "ROHM Semiconductor" (at 126.365 132.715 0)
      (effects (font (size 1.27 1.27) (thickness 0.15)) (justify left bottom) hide)
    )
    (property "MPN" "DTC014TEBTL" (at 111.125 118.7449 0)
      (effects (font (size 1.27 1.27) (thickness 0.15)) (justify left))
    )
    (property "Author" "Antmicro" (at 126.365 137.795 0)
      (effects (font (size 1.27 1.27) (thickness 0.15)) (justify left bottom) hide)
    )
    (property "License" "Apache-2.0" (at 126.365 140.335 0)
      (effects (font (size 1.27 1.27) (thickness 0.15)) (justify left bottom) hide)
    )
    (pin "1")
    (pin "2")
    (pin "3")
    (instances
      (project "kria-k26-devboard"
        (path ""
          (reference "Q3") (unit 1)
        )
      )
    )
  )

  (symbol (lib_id "kria-k26-devboard:NB3L202KMN") (at 134.62 97.155 0) (unit 1)
    (in_bom yes) (on_board yes) (dnp no) (fields_autoplaced)
    (property "Reference" "U7" (at 144.145 88.9 0)
      (effects (font (size 1.524 1.524)))
    )
    (property "Value" "NB3L202KMN" (at 144.145 91.44 0)
      (effects (font (size 1.27 1.27) (thickness 0.15)))
    )
    (property "Footprint" "kria-k26-devboard-footprints:VQFN-16-1EP_3x3mm_P0.5mm_EP1.68x1.68mm" (at 190.5 109.855 0)
      (effects (font (size 1.27 1.27) (thickness 0.15)) (justify left bottom) hide)
    )
    (property "Datasheet" "https://www.mouser.com/datasheet/2/308/1/NB3L202K_D-2316569.pdf" (at 190.5 112.395 0)
      (effects (font (size 1.27 1.27) (thickness 0.15)) (justify left bottom) hide)
    )
    (property "MPN" "NB3L202KMNTXG" (at 190.5 114.935 0)
      (effects (font (size 1.27 1.27) (thickness 0.15)) (justify left bottom) hide)
    )
    (property "Manufacturer" "ON Semiconductor" (at 190.5 117.475 0)
      (effects (font (size 1.27 1.27) (thickness 0.15)) (justify left bottom) hide)
    )
    (property "Author" "Antmicro" (at 190.5 120.015 0)
      (effects (font (size 1.27 1.27) (thickness 0.15)) (justify left bottom) hide)
    )
    (property "License" "Apache-2.0" (at 190.5 122.555 0)
      (effects (font (size 1.27 1.27) (thickness 0.15)) (justify left bottom) hide)
    )
    (pin "1")
    (pin "10")
    (pin "11")
    (pin "12")
    (pin "13")
    (pin "14")
    (pin "15")
    (pin "16")
    (pin "17")
    (pin "2")
    (pin "3")
    (pin "4")
    (pin "5")
    (pin "6")
    (pin "7")
    (pin "8")
    (pin "9")
    (instances
      (project "kria-k26-devboard"
        (path ""
          (reference "U7") (unit 1)
        )
      )
    )
  )

  (symbol (lib_id "kria-k26-devboard:Oscillator_100MHz_NX324") (at 78.105 82.55 0) (unit 1)
    (in_bom yes) (on_board yes) (dnp no) (fields_autoplaced)
    (property "Reference" "Y1" (at 87.63 72.39 0)
      (effects (font (size 1.524 1.524)))
    )
    (property "Value" "Oscillator_100MHz_NX324" (at 87.63 78.74 0)
      (effects (font (size 1.27 1.27) (thickness 0.15)) hide)
    )
    (property "Footprint" "kria-k26-devboard-footprints:Oscillator_SMD_Abracon_AX3_3.2x2.5x1mm" (at 111.125 92.71 0)
      (effects (font (size 1.27 1.27) (thickness 0.15)) (justify left bottom) hide)
    )
    (property "Datasheet" "https://www.diodes.com/assets/Datasheets/NX324.pdf" (at 111.125 95.25 0)
      (effects (font (size 1.27 1.27) (thickness 0.15)) (justify left bottom) hide)
    )
    (property "MPN" "NX3241E0100.000000" (at 87.63 74.93 0)
      (effects (font (size 1.27 1.27) (thickness 0.15)))
    )
    (property "Manufacturer" "Diodes Incorporated" (at 111.125 100.33 0)
      (effects (font (size 1.27 1.27) (thickness 0.15)) (justify left bottom) hide)
    )
    (property "Author" "Antmicro" (at 111.125 102.87 0)
      (effects (font (size 1.27 1.27) (thickness 0.15)) (justify left bottom) hide)
    )
    (property "License" "Apache-2.0" (at 111.125 105.41 0)
      (effects (font (size 1.27 1.27) (thickness 0.15)) (justify left bottom) hide)
    )
    (property "Val" "100 MHz" (at 87.63 77.47 0)
      (effects (font (size 1.27 1.27) (thickness 0.15)))
    )
    (pin "1")
    (pin "2")
    (pin "3")
    (pin "4")
    (pin "5")
    (pin "6")
    (instances
      (project "kria-k26-devboard"
        (path ""
          (reference "Y1") (unit 1)
        )
      )
    )
  )

  (symbol (lib_id "kria-k26-devboard:GND") (at 135.255 78.74 0) (unit 1)
    (in_bom yes) (on_board yes) (dnp no) (fields_autoplaced)
    (property "Reference" "#PWR040" (at 135.255 85.09 0)
      (effects (font (size 1.27 1.27)) hide)
    )
    (property "Value" "GND" (at 135.255 83.82 0)
      (effects (font (size 1.27 1.27)))
    )
    (property "Footprint" "" (at 144.145 86.36 0)
      (effects (font (size 1.27 1.27) (thickness 0.15)) (justify left bottom) hide)
    )
    (property "Datasheet" "" (at 144.145 91.44 0)
      (effects (font (size 1.27 1.27) (thickness 0.15)) (justify left bottom) hide)
    )
    (property "Author" "Antmicro" (at 144.145 86.36 0)
      (effects (font (size 1.27 1.27) (thickness 0.15)) (justify left bottom) hide)
    )
    (property "License" "Apache-2.0" (at 144.145 88.9 0)
      (effects (font (size 1.27 1.27) (thickness 0.15)) (justify left bottom) hide)
    )
    (pin "1")
    (instances
      (project "kria-k26-devboard"
        (path ""
          (reference "#PWR040") (unit 1)
        )
      )
    )
  )

  (symbol (lib_id "kria-k26-devboard:C_100n_0402") (at 135.255 73.66 270) (unit 1)
    (in_bom yes) (on_board yes) (dnp no) (fields_autoplaced)
    (property "Reference" "C23" (at 137.795 74.9363 90)
      (effects (font (size 1.524 1.524)) (justify left))
    )
    (property "Value" "C_100n_0402" (at 125.095 93.98 0)
      (effects (font (size 1.27 1.27) (thickness 0.15)) (justify left bottom) hide)
    )
    (property "Footprint" "kria-k26-devboard-footprints:C_0402_1005Metric" (at 122.555 93.98 0)
      (effects (font (size 1.27 1.27) (thickness 0.15)) (justify left bottom) hide)
    )
    (property "Datasheet" "https://search.murata.co.jp/Ceramy/image/img/A01X/G101/ENG/GRM155R61H104KE14-01.pdf" (at 120.015 93.98 0)
      (effects (font (size 1.27 1.27) (thickness 0.15)) (justify left bottom) hide)
    )
    (property "Manufacturer" "Murata" (at 114.935 93.98 0)
      (effects (font (size 1.27 1.27) (thickness 0.15)) (justify left bottom) hide)
    )
    (property "MPN" "GRM155R61H104KE14D" (at 117.475 93.98 0)
      (effects (font (size 1.27 1.27) (thickness 0.15)) (justify left bottom) hide)
    )
    (property "Val" "100n" (at 137.795 78.1112 90)
      (effects (font (size 1.27 1.27) (thickness 0.15)) (justify left))
    )
    (property "License" "Apache-2.0" (at 112.395 93.98 0)
      (effects (font (size 1.27 1.27) (thickness 0.15)) (justify left bottom) hide)
    )
    (property "Author" "Antmicro" (at 109.855 93.98 0)
      (effects (font (size 1.27 1.27) (thickness 0.15)) (justify left bottom) hide)
    )
    (property "Voltage" "50V" (at 107.315 93.98 0)
      (effects (font (size 1.27 1.27)) (justify left bottom) hide)
    )
    (property "Dielectric" "X5R" (at 104.775 93.98 0)
      (effects (font (size 1.27 1.27)) (justify left bottom) hide)
    )
    (pin "1")
    (pin "2")
    (instances
      (project "kria-k26-devboard"
        (path ""
          (reference "C23") (unit 1)
        )
      )
    )
  )

  (symbol (lib_id "kria-k26-devboard:GND") (at 145.415 78.74 0) (unit 1)
    (in_bom yes) (on_board yes) (dnp no) (fields_autoplaced)
    (property "Reference" "#PWR041" (at 145.415 85.09 0)
      (effects (font (size 1.27 1.27)) hide)
    )
    (property "Value" "GND" (at 145.415 83.82 0)
      (effects (font (size 1.27 1.27)))
    )
    (property "Footprint" "" (at 154.305 86.36 0)
      (effects (font (size 1.27 1.27) (thickness 0.15)) (justify left bottom) hide)
    )
    (property "Datasheet" "" (at 154.305 91.44 0)
      (effects (font (size 1.27 1.27) (thickness 0.15)) (justify left bottom) hide)
    )
    (property "Author" "Antmicro" (at 154.305 86.36 0)
      (effects (font (size 1.27 1.27) (thickness 0.15)) (justify left bottom) hide)
    )
    (property "License" "Apache-2.0" (at 154.305 88.9 0)
      (effects (font (size 1.27 1.27) (thickness 0.15)) (justify left bottom) hide)
    )
    (pin "1")
    (instances
      (project "kria-k26-devboard"
        (path ""
          (reference "#PWR041") (unit 1)
        )
      )
    )
  )

  (symbol (lib_id "kria-k26-devboard:C_100n_0402") (at 145.415 73.66 270) (unit 1)
    (in_bom yes) (on_board yes) (dnp no) (fields_autoplaced)
    (property "Reference" "C24" (at 147.955 74.9363 90)
      (effects (font (size 1.524 1.524)) (justify left))
    )
    (property "Value" "C_100n_0402" (at 135.255 93.98 0)
      (effects (font (size 1.27 1.27) (thickness 0.15)) (justify left bottom) hide)
    )
    (property "Footprint" "kria-k26-devboard-footprints:C_0402_1005Metric" (at 132.715 93.98 0)
      (effects (font (size 1.27 1.27) (thickness 0.15)) (justify left bottom) hide)
    )
    (property "Datasheet" "https://search.murata.co.jp/Ceramy/image/img/A01X/G101/ENG/GRM155R61H104KE14-01.pdf" (at 130.175 93.98 0)
      (effects (font (size 1.27 1.27) (thickness 0.15)) (justify left bottom) hide)
    )
    (property "Manufacturer" "Murata" (at 125.095 93.98 0)
      (effects (font (size 1.27 1.27) (thickness 0.15)) (justify left bottom) hide)
    )
    (property "MPN" "GRM155R61H104KE14D" (at 127.635 93.98 0)
      (effects (font (size 1.27 1.27) (thickness 0.15)) (justify left bottom) hide)
    )
    (property "Val" "100n" (at 147.955 78.1112 90)
      (effects (font (size 1.27 1.27) (thickness 0.15)) (justify left))
    )
    (property "License" "Apache-2.0" (at 122.555 93.98 0)
      (effects (font (size 1.27 1.27) (thickness 0.15)) (justify left bottom) hide)
    )
    (property "Author" "Antmicro" (at 120.015 93.98 0)
      (effects (font (size 1.27 1.27) (thickness 0.15)) (justify left bottom) hide)
    )
    (property "Voltage" "50V" (at 117.475 93.98 0)
      (effects (font (size 1.27 1.27)) (justify left bottom) hide)
    )
    (property "Dielectric" "X5R" (at 114.935 93.98 0)
      (effects (font (size 1.27 1.27)) (justify left bottom) hide)
    )
    (pin "1")
    (pin "2")
    (instances
      (project "kria-k26-devboard"
        (path ""
          (reference "C24") (unit 1)
        )
      )
    )
  )

  (symbol (lib_id "kria-k26-devboard:GND") (at 99.06 92.71 0) (unit 1)
    (in_bom yes) (on_board yes) (dnp no) (fields_autoplaced)
    (property "Reference" "#PWR037" (at 99.06 99.06 0)
      (effects (font (size 1.27 1.27)) hide)
    )
    (property "Value" "GND" (at 99.06 97.79 0)
      (effects (font (size 1.27 1.27)))
    )
    (property "Footprint" "" (at 107.95 100.33 0)
      (effects (font (size 1.27 1.27) (thickness 0.15)) (justify left bottom) hide)
    )
    (property "Datasheet" "" (at 107.95 105.41 0)
      (effects (font (size 1.27 1.27) (thickness 0.15)) (justify left bottom) hide)
    )
    (property "Author" "Antmicro" (at 107.95 100.33 0)
      (effects (font (size 1.27 1.27) (thickness 0.15)) (justify left bottom) hide)
    )
    (property "License" "Apache-2.0" (at 107.95 102.87 0)
      (effects (font (size 1.27 1.27) (thickness 0.15)) (justify left bottom) hide)
    )
    (pin "1")
    (instances
      (project "kria-k26-devboard"
        (path ""
          (reference "#PWR037") (unit 1)
        )
      )
    )
  )

  (symbol (lib_id "kria-k26-devboard:GND") (at 160.655 120.65 0) (unit 1)
    (in_bom yes) (on_board yes) (dnp no) (fields_autoplaced)
    (property "Reference" "#PWR046" (at 160.655 127 0)
      (effects (font (size 1.27 1.27)) hide)
    )
    (property "Value" "GND" (at 160.655 125.73 0)
      (effects (font (size 1.27 1.27)))
    )
    (property "Footprint" "" (at 169.545 128.27 0)
      (effects (font (size 1.27 1.27) (thickness 0.15)) (justify left bottom) hide)
    )
    (property "Datasheet" "" (at 169.545 133.35 0)
      (effects (font (size 1.27 1.27) (thickness 0.15)) (justify left bottom) hide)
    )
    (property "Author" "Antmicro" (at 169.545 128.27 0)
      (effects (font (size 1.27 1.27) (thickness 0.15)) (justify left bottom) hide)
    )
    (property "License" "Apache-2.0" (at 169.545 130.81 0)
      (effects (font (size 1.27 1.27) (thickness 0.15)) (justify left bottom) hide)
    )
    (pin "1")
    (instances
      (project "kria-k26-devboard"
        (path ""
          (reference "#PWR046") (unit 1)
        )
      )
    )
  )

  (symbol (lib_id "kria-k26-devboard:C_100n_0402") (at 155.575 73.66 270) (unit 1)
    (in_bom yes) (on_board yes) (dnp no) (fields_autoplaced)
    (property "Reference" "C26" (at 158.115 74.9363 90)
      (effects (font (size 1.524 1.524)) (justify left))
    )
    (property "Value" "C_100n_0402" (at 145.415 93.98 0)
      (effects (font (size 1.27 1.27) (thickness 0.15)) (justify left bottom) hide)
    )
    (property "Footprint" "kria-k26-devboard-footprints:C_0402_1005Metric" (at 142.875 93.98 0)
      (effects (font (size 1.27 1.27) (thickness 0.15)) (justify left bottom) hide)
    )
    (property "Datasheet" "https://search.murata.co.jp/Ceramy/image/img/A01X/G101/ENG/GRM155R61H104KE14-01.pdf" (at 140.335 93.98 0)
      (effects (font (size 1.27 1.27) (thickness 0.15)) (justify left bottom) hide)
    )
    (property "Manufacturer" "Murata" (at 135.255 93.98 0)
      (effects (font (size 1.27 1.27) (thickness 0.15)) (justify left bottom) hide)
    )
    (property "MPN" "GRM155R61H104KE14D" (at 137.795 93.98 0)
      (effects (font (size 1.27 1.27) (thickness 0.15)) (justify left bottom) hide)
    )
    (property "Val" "100n" (at 158.115 78.1112 90)
      (effects (font (size 1.27 1.27) (thickness 0.15)) (justify left))
    )
    (property "License" "Apache-2.0" (at 132.715 93.98 0)
      (effects (font (size 1.27 1.27) (thickness 0.15)) (justify left bottom) hide)
    )
    (property "Author" "Antmicro" (at 130.175 93.98 0)
      (effects (font (size 1.27 1.27) (thickness 0.15)) (justify left bottom) hide)
    )
    (property "Voltage" "50V" (at 127.635 93.98 0)
      (effects (font (size 1.27 1.27)) (justify left bottom) hide)
    )
    (property "Dielectric" "X5R" (at 125.095 93.98 0)
      (effects (font (size 1.27 1.27)) (justify left bottom) hide)
    )
    (pin "1")
    (pin "2")
    (instances
      (project "kria-k26-devboard"
        (path ""
          (reference "C26") (unit 1)
        )
      )
    )
  )

  (symbol (lib_id "kria-k26-devboard:GND") (at 155.575 78.74 0) (unit 1)
    (in_bom yes) (on_board yes) (dnp no) (fields_autoplaced)
    (property "Reference" "#PWR043" (at 155.575 85.09 0)
      (effects (font (size 1.27 1.27)) hide)
    )
    (property "Value" "GND" (at 155.575 83.82 0)
      (effects (font (size 1.27 1.27)))
    )
    (property "Footprint" "" (at 164.465 86.36 0)
      (effects (font (size 1.27 1.27) (thickness 0.15)) (justify left bottom) hide)
    )
    (property "Datasheet" "" (at 164.465 91.44 0)
      (effects (font (size 1.27 1.27) (thickness 0.15)) (justify left bottom) hide)
    )
    (property "Author" "Antmicro" (at 164.465 86.36 0)
      (effects (font (size 1.27 1.27) (thickness 0.15)) (justify left bottom) hide)
    )
    (property "License" "Apache-2.0" (at 164.465 88.9 0)
      (effects (font (size 1.27 1.27) (thickness 0.15)) (justify left bottom) hide)
    )
    (pin "1")
    (instances
      (project "kria-k26-devboard"
        (path ""
          (reference "#PWR043") (unit 1)
        )
      )
    )
  )

  (symbol (lib_id "kria-k26-devboard:GND") (at 155.575 120.65 0) (unit 1)
    (in_bom yes) (on_board yes) (dnp no) (fields_autoplaced)
    (property "Reference" "#PWR045" (at 155.575 127 0)
      (effects (font (size 1.27 1.27)) hide)
    )
    (property "Value" "GND" (at 155.575 125.73 0)
      (effects (font (size 1.27 1.27)))
    )
    (property "Footprint" "" (at 164.465 128.27 0)
      (effects (font (size 1.27 1.27) (thickness 0.15)) (justify left bottom) hide)
    )
    (property "Datasheet" "" (at 164.465 133.35 0)
      (effects (font (size 1.27 1.27) (thickness 0.15)) (justify left bottom) hide)
    )
    (property "Author" "Antmicro" (at 164.465 128.27 0)
      (effects (font (size 1.27 1.27) (thickness 0.15)) (justify left bottom) hide)
    )
    (property "License" "Apache-2.0" (at 164.465 130.81 0)
      (effects (font (size 1.27 1.27) (thickness 0.15)) (justify left bottom) hide)
    )
    (pin "1")
    (instances
      (project "kria-k26-devboard"
        (path ""
          (reference "#PWR045") (unit 1)
        )
      )
    )
  )

  (symbol (lib_id "kria-k26-devboard:GND") (at 74.295 104.775 0) (unit 1)
    (in_bom yes) (on_board yes) (dnp no) (fields_autoplaced)
    (property "Reference" "#PWR034" (at 74.295 111.125 0)
      (effects (font (size 1.27 1.27)) hide)
    )
    (property "Value" "GND" (at 74.295 109.855 0)
      (effects (font (size 1.27 1.27)))
    )
    (property "Footprint" "" (at 83.185 112.395 0)
      (effects (font (size 1.27 1.27) (thickness 0.15)) (justify left bottom) hide)
    )
    (property "Datasheet" "" (at 83.185 117.475 0)
      (effects (font (size 1.27 1.27) (thickness 0.15)) (justify left bottom) hide)
    )
    (property "Author" "Antmicro" (at 83.185 112.395 0)
      (effects (font (size 1.27 1.27) (thickness 0.15)) (justify left bottom) hide)
    )
    (property "License" "Apache-2.0" (at 83.185 114.935 0)
      (effects (font (size 1.27 1.27) (thickness 0.15)) (justify left bottom) hide)
    )
    (pin "1")
    (instances
      (project "kria-k26-devboard"
        (path ""
          (reference "#PWR034") (unit 1)
        )
      )
    )
  )

  (symbol (lib_id "kria-k26-devboard:C_100n_0402") (at 74.295 99.695 270) (unit 1)
    (in_bom yes) (on_board yes) (dnp no) (fields_autoplaced)
    (property "Reference" "C21" (at 76.835 100.9713 90)
      (effects (font (size 1.524 1.524)) (justify left))
    )
    (property "Value" "C_100n_0402" (at 64.135 120.015 0)
      (effects (font (size 1.27 1.27) (thickness 0.15)) (justify left bottom) hide)
    )
    (property "Footprint" "kria-k26-devboard-footprints:C_0402_1005Metric" (at 61.595 120.015 0)
      (effects (font (size 1.27 1.27) (thickness 0.15)) (justify left bottom) hide)
    )
    (property "Datasheet" "https://search.murata.co.jp/Ceramy/image/img/A01X/G101/ENG/GRM155R61H104KE14-01.pdf" (at 59.055 120.015 0)
      (effects (font (size 1.27 1.27) (thickness 0.15)) (justify left bottom) hide)
    )
    (property "Manufacturer" "Murata" (at 53.975 120.015 0)
      (effects (font (size 1.27 1.27) (thickness 0.15)) (justify left bottom) hide)
    )
    (property "MPN" "GRM155R61H104KE14D" (at 56.515 120.015 0)
      (effects (font (size 1.27 1.27) (thickness 0.15)) (justify left bottom) hide)
    )
    (property "Val" "100n" (at 76.835 104.1462 90)
      (effects (font (size 1.27 1.27) (thickness 0.15)) (justify left))
    )
    (property "License" "Apache-2.0" (at 51.435 120.015 0)
      (effects (font (size 1.27 1.27) (thickness 0.15)) (justify left bottom) hide)
    )
    (property "Author" "Antmicro" (at 48.895 120.015 0)
      (effects (font (size 1.27 1.27) (thickness 0.15)) (justify left bottom) hide)
    )
    (property "Voltage" "50V" (at 46.355 120.015 0)
      (effects (font (size 1.27 1.27)) (justify left bottom) hide)
    )
    (property "Dielectric" "X5R" (at 43.815 120.015 0)
      (effects (font (size 1.27 1.27)) (justify left bottom) hide)
    )
    (pin "1")
    (pin "2")
    (instances
      (project "kria-k26-devboard"
        (path ""
          (reference "C21") (unit 1)
        )
      )
    )
  )

  (symbol (lib_id "kria-k26-devboard:GND") (at 108.585 122.555 0) (unit 1)
    (in_bom yes) (on_board yes) (dnp no) (fields_autoplaced)
    (property "Reference" "#PWR036" (at 108.585 128.905 0)
      (effects (font (size 1.27 1.27)) hide)
    )
    (property "Value" "GND" (at 108.585 127.635 0)
      (effects (font (size 1.27 1.27)))
    )
    (property "Footprint" "" (at 117.475 130.175 0)
      (effects (font (size 1.27 1.27) (thickness 0.15)) (justify left bottom) hide)
    )
    (property "Datasheet" "" (at 117.475 135.255 0)
      (effects (font (size 1.27 1.27) (thickness 0.15)) (justify left bottom) hide)
    )
    (property "Author" "Antmicro" (at 117.475 130.175 0)
      (effects (font (size 1.27 1.27) (thickness 0.15)) (justify left bottom) hide)
    )
    (property "License" "Apache-2.0" (at 117.475 132.715 0)
      (effects (font (size 1.27 1.27) (thickness 0.15)) (justify left bottom) hide)
    )
    (pin "1")
    (instances
      (project "kria-k26-devboard"
        (path ""
          (reference "#PWR036") (unit 1)
        )
      )
    )
  )

  (symbol (lib_id "kria-k26-devboard:R_10k_0402") (at 108.585 103.505 270) (unit 1)
    (in_bom yes) (on_board yes) (dnp no) (fields_autoplaced)
    (property "Reference" "R19" (at 106.045 104.775 90)
      (effects (font (size 1.524 1.524)) (justify right))
    )
    (property "Value" "R_10k_0402" (at 95.885 123.825 0)
      (effects (font (size 1.27 1.27) (thickness 0.15)) (justify left bottom) hide)
    )
    (property "Footprint" "kria-k26-devboard-footprints:R_0402_1005Metric" (at 93.345 123.825 0)
      (effects (font (size 1.27 1.27) (thickness 0.15)) (justify left bottom) hide)
    )
    (property "Datasheet" "https://www.bourns.com/docs/product-datasheets/cr.pdf" (at 90.805 123.825 0)
      (effects (font (size 1.27 1.27) (thickness 0.15)) (justify left bottom) hide)
    )
    (property "Manufacturer" "Bourns" (at 85.725 123.825 0)
      (effects (font (size 1.27 1.27) (thickness 0.15)) (justify left bottom) hide)
    )
    (property "MPN" "CR0402-FX-1002GLF" (at 88.265 123.825 0)
      (effects (font (size 1.27 1.27) (thickness 0.15)) (justify left bottom) hide)
    )
    (property "Val" "10k" (at 106.045 107.9499 90)
      (effects (font (size 1.27 1.27) (thickness 0.15)) (justify right))
    )
    (property "License" "Apache-2.0" (at 83.185 123.825 0)
      (effects (font (size 1.27 1.27) (thickness 0.15)) (justify left bottom) hide)
    )
    (property "Author" "Antmicro" (at 80.645 123.825 0)
      (effects (font (size 1.27 1.27) (thickness 0.15)) (justify left bottom) hide)
    )
    (property "Tolerance" "1%" (at 98.425 123.825 0)
      (effects (font (size 1.27 1.27)) (justify left bottom) hide)
    )
    (pin "1")
    (pin "2")
    (instances
      (project "kria-k26-devboard"
        (path ""
          (reference "R19") (unit 1)
        )
      )
    )
  )

  (symbol (lib_id "kria-k26-devboard:R_49R9_0402") (at 99.06 92.71 90) (unit 1)
    (in_bom yes) (on_board yes) (dnp no)
    (property "Reference" "R20" (at 100.33 88.9 90)
      (effects (font (size 1.524 1.524)) (justify right))
    )
    (property "Value" "R_49R9_0402" (at 111.76 72.39 0)
      (effects (font (size 1.27 1.27) (thickness 0.15)) (justify left bottom) hide)
    )
    (property "Footprint" "kria-k26-devboard-footprints:R_0402_1005Metric" (at 114.3 72.39 0)
      (effects (font (size 1.27 1.27) (thickness 0.15)) (justify left bottom) hide)
    )
    (property "Datasheet" "https://www.bourns.com/docs/product-datasheets/cr.pdf" (at 116.84 72.39 0)
      (effects (font (size 1.27 1.27) (thickness 0.15)) (justify left bottom) hide)
    )
    (property "Manufacturer" "Bourns" (at 121.92 72.39 0)
      (effects (font (size 1.27 1.27) (thickness 0.15)) (justify left bottom) hide)
    )
    (property "MPN" "CR0402-FX-49R9GLF" (at 119.38 72.39 0)
      (effects (font (size 1.27 1.27) (thickness 0.15)) (justify left bottom) hide)
    )
    (property "Val" "49R9" (at 100.33 91.44 90)
      (effects (font (size 1.27 1.27) (thickness 0.15)) (justify right))
    )
    (property "License" "Apache-2.0" (at 124.46 72.39 0)
      (effects (font (size 1.27 1.27) (thickness 0.15)) (justify left bottom) hide)
    )
    (property "Author" "Antmicro" (at 127 72.39 0)
      (effects (font (size 1.27 1.27) (thickness 0.15)) (justify left bottom) hide)
    )
    (property "Tolerance" "1%" (at 109.22 72.39 0)
      (effects (font (size 1.27 1.27)) (justify left bottom) hide)
    )
    (pin "1")
    (pin "2")
    (instances
      (project "kria-k26-devboard"
        (path ""
          (reference "R20") (unit 1)
        )
      )
    )
  )

  (symbol (lib_id "kria-k26-devboard:GND") (at 76.2 88.9 0) (unit 1)
    (in_bom yes) (on_board yes) (dnp no) (fields_autoplaced)
    (property "Reference" "#PWR0367" (at 76.2 95.25 0)
      (effects (font (size 1.27 1.27)) hide)
    )
    (property "Value" "GND" (at 76.2 93.98 0)
      (effects (font (size 1.27 1.27)))
    )
    (property "Footprint" "" (at 85.09 96.52 0)
      (effects (font (size 1.27 1.27) (thickness 0.15)) (justify left bottom) hide)
    )
    (property "Datasheet" "" (at 85.09 101.6 0)
      (effects (font (size 1.27 1.27) (thickness 0.15)) (justify left bottom) hide)
    )
    (property "Author" "Antmicro" (at 85.09 96.52 0)
      (effects (font (size 1.27 1.27) (thickness 0.15)) (justify left bottom) hide)
    )
    (property "License" "Apache-2.0" (at 85.09 99.06 0)
      (effects (font (size 1.27 1.27) (thickness 0.15)) (justify left bottom) hide)
    )
    (pin "1")
    (instances
      (project "kria-k26-devboard"
        (path ""
          (reference "#PWR0367") (unit 1)
        )
      )
    )
  )

  (symbol (lib_id "kria-k26-devboard:R_100k_0402") (at 137.795 186.055 90) (unit 1)
    (in_bom no) (on_board yes) (dnp yes)
    (property "Reference" "R176" (at 139.7 182.245 90)
      (effects (font (size 1.524 1.524)) (justify right))
    )
    (property "Value" "R_100k_0402" (at 150.495 165.735 0)
      (effects (font (size 1.27 1.27) (thickness 0.15)) (justify left bottom) hide)
    )
    (property "Footprint" "kria-k26-devboard-footprints:R_0402_1005Metric" (at 153.035 165.735 0)
      (effects (font (size 1.27 1.27) (thickness 0.15)) (justify left bottom) hide)
    )
    (property "Datasheet" "https://www.bourns.com/docs/product-datasheets/cr.pdf" (at 155.575 165.735 0)
      (effects (font (size 1.27 1.27) (thickness 0.15)) (justify left bottom) hide)
    )
    (property "Manufacturer" "Bourns" (at 160.655 165.735 0)
      (effects (font (size 1.27 1.27) (thickness 0.15)) (justify left bottom) hide)
    )
    (property "MPN" "CR0402-FX-1003GLF" (at 158.115 165.735 0)
      (effects (font (size 1.27 1.27) (thickness 0.15)) (justify left bottom) hide)
    )
    (property "Val" "100k" (at 139.7 184.1499 90)
      (effects (font (size 1.27 1.27) (thickness 0.15)) (justify right))
    )
    (property "DNP" "DNP" (at 137.795 181.61 0)
      (effects (font (size 1.27 1.27)) (justify right))
    )
    (property "License" "Apache-2.0" (at 163.195 165.735 0)
      (effects (font (size 1.27 1.27) (thickness 0.15)) (justify left bottom) hide)
    )
    (property "Author" "Antmicro" (at 165.735 165.735 0)
      (effects (font (size 1.27 1.27) (thickness 0.15)) (justify left bottom) hide)
    )
    (property "Tolerance" "1%" (at 147.955 165.735 0)
      (effects (font (size 1.27 1.27)) (justify left bottom) hide)
    )
    (pin "1")
    (pin "2")
    (instances
      (project "kria-k26-devboard"
        (path ""
          (reference "R176") (unit 1)
        )
      )
    )
  )

  (symbol (lib_id "kria-k26-devboard:GND") (at 137.795 186.055 0) (unit 1)
    (in_bom yes) (on_board yes) (dnp no) (fields_autoplaced)
    (property "Reference" "#PWR0413" (at 137.795 192.405 0)
      (effects (font (size 1.27 1.27)) hide)
    )
    (property "Value" "GND" (at 137.795 190.5 0)
      (effects (font (size 1.27 1.27)))
    )
    (property "Footprint" "" (at 146.685 193.675 0)
      (effects (font (size 1.27 1.27) (thickness 0.15)) (justify left bottom) hide)
    )
    (property "Datasheet" "" (at 146.685 198.755 0)
      (effects (font (size 1.27 1.27) (thickness 0.15)) (justify left bottom) hide)
    )
    (property "Author" "Antmicro" (at 146.685 193.675 0)
      (effects (font (size 1.27 1.27) (thickness 0.15)) (justify left bottom) hide)
    )
    (property "License" "Apache-2.0" (at 146.685 196.215 0)
      (effects (font (size 1.27 1.27) (thickness 0.15)) (justify left bottom) hide)
    )
    (pin "1")
    (instances
      (project "kria-k26-devboard"
        (path ""
          (reference "#PWR0413") (unit 1)
        )
      )
    )
  )

  (symbol (lib_id "kria-k26-devboard:R_49R9_0402") (at 107.315 92.71 90) (unit 1)
    (in_bom yes) (on_board yes) (dnp no)
    (property "Reference" "R21" (at 108.585 88.9 90)
      (effects (font (size 1.524 1.524)) (justify right))
    )
    (property "Value" "R_49R9_0402" (at 120.015 72.39 0)
      (effects (font (size 1.27 1.27) (thickness 0.15)) (justify left bottom) hide)
    )
    (property "Footprint" "kria-k26-devboard-footprints:R_0402_1005Metric" (at 122.555 72.39 0)
      (effects (font (size 1.27 1.27) (thickness 0.15)) (justify left bottom) hide)
    )
    (property "Datasheet" "https://www.bourns.com/docs/product-datasheets/cr.pdf" (at 125.095 72.39 0)
      (effects (font (size 1.27 1.27) (thickness 0.15)) (justify left bottom) hide)
    )
    (property "Manufacturer" "Bourns" (at 130.175 72.39 0)
      (effects (font (size 1.27 1.27) (thickness 0.15)) (justify left bottom) hide)
    )
    (property "MPN" "CR0402-FX-49R9GLF" (at 127.635 72.39 0)
      (effects (font (size 1.27 1.27) (thickness 0.15)) (justify left bottom) hide)
    )
    (property "Val" "49R9" (at 108.585 91.44 90)
      (effects (font (size 1.27 1.27) (thickness 0.15)) (justify right))
    )
    (property "License" "Apache-2.0" (at 132.715 72.39 0)
      (effects (font (size 1.27 1.27) (thickness 0.15)) (justify left bottom) hide)
    )
    (property "Author" "Antmicro" (at 135.255 72.39 0)
      (effects (font (size 1.27 1.27) (thickness 0.15)) (justify left bottom) hide)
    )
    (property "Tolerance" "1%" (at 117.475 72.39 0)
      (effects (font (size 1.27 1.27)) (justify left bottom) hide)
    )
    (pin "1")
    (pin "2")
    (instances
      (project "kria-k26-devboard"
        (path ""
          (reference "R21") (unit 1)
        )
      )
    )
  )

  (symbol (lib_id "kria-k26-devboard:GND") (at 107.315 92.71 0) (unit 1)
    (in_bom yes) (on_board yes) (dnp no) (fields_autoplaced)
    (property "Reference" "#PWR0366" (at 107.315 99.06 0)
      (effects (font (size 1.27 1.27)) hide)
    )
    (property "Value" "GND" (at 107.315 97.79 0)
      (effects (font (size 1.27 1.27)))
    )
    (property "Footprint" "" (at 116.205 100.33 0)
      (effects (font (size 1.27 1.27) (thickness 0.15)) (justify left bottom) hide)
    )
    (property "Datasheet" "" (at 116.205 105.41 0)
      (effects (font (size 1.27 1.27) (thickness 0.15)) (justify left bottom) hide)
    )
    (property "Author" "Antmicro" (at 116.205 100.33 0)
      (effects (font (size 1.27 1.27) (thickness 0.15)) (justify left bottom) hide)
    )
    (property "License" "Apache-2.0" (at 116.205 102.87 0)
      (effects (font (size 1.27 1.27) (thickness 0.15)) (justify left bottom) hide)
    )
    (pin "1")
    (instances
      (project "kria-k26-devboard"
        (path ""
          (reference "#PWR0366") (unit 1)
        )
      )
    )
  )
)
